#ISCELL
  mstr_misc dns *
  *
#ISCELL
  pure_quanta quanta_title_block_c *
  *
#ISCELL
  logical_power universal_gnd *
  page273_i1
#ISCELL
  standard offpage *
  page273_i10
#ISCELL
  standard offpage *
  page273_i11
#ISCELL
  standard offpage *
  page273_i12
#ISCELL
  standard offpage *
  page273_i13
#ISCELL
  standard offpage *
  page273_i14
#CELL
  pure_quanta q_cap *
  page273_i15
#CELL
  pure_quanta isl99390frztr5935 *
  page273_i16
#CELL
  pure_quanta q_cap *
  page273_i17
#ISCELL
  logical_power universal_gnd *
  page273_i18
#CELL
  pure_quanta q_res *
  page273_i19
#CELL
  pure_quanta q_res *
  page273_i2
#ISCELL
  logical_power universal_gnd *
  page273_i20
#CELL
  pure_quanta q_cap *
  page273_i21
#ISCELL
  logical_power vcc15 *
  page273_i22
#CELL
  pure_quanta isl99390frztr5935 *
  page273_i23
#ISCELL
  logical_power universal_gnd *
  page273_i24
#ISCELL
  standard offpage *
  page273_i25
#CELL
  pure_quanta q_cap *
  page273_i26
#CELL
  pure_quanta q_res *
  page273_i27
#CELL
  pure_quanta q_inductor4p_14 *
  page273_i28
#CELL
  pure_quanta q_cap *
  page273_i29
#ISCELL
  standard offpage *
  page273_i3
#CELL
  pure_quanta q_res *
  page273_i30
#CELL
  pure_quanta q_cap *
  page273_i31
#ISCELL
  logical_power universal_gnd *
  page273_i32
#CELL
  pure_quanta q_cap *
  page273_i33
#CELL
  pure_quanta q_cap *
  page273_i34
#CELL
  pure_quanta q_cap *
  page273_i35
#CELL
  pure_quanta q_cap *
  page273_i36
#CELL
  pure_quanta q_cap *
  page273_i37
#ISCELL
  logical_power universal_gnd *
  page273_i38
#CELL
  pure_quanta q_res *
  page273_i39
#ISCELL
  logical_power universal_gnd *
  page273_i4
#ISCELL
  logical_power universal_gnd *
  page273_i40
#CELL
  pure_quanta q_cap *
  page273_i41
#ISCELL
  logical_power vcc15 *
  page273_i42
#ISCELL
  standard offpage *
  page273_i43
#CELL
  pure_quanta q_res *
  page273_i44
#CELL
  pure_quanta q_cap *
  page273_i45
#CELL
  pure_quanta q_cap *
  page273_i46
#CELL
  pure_quanta q_cap *
  page273_i47
#CELL
  pure_quanta q_inductor4p_14 *
  page273_i48
#CELL
  pure_quanta q_res *
  page273_i49
#ISCELL
  standard offpage *
  page273_i5
#CELL
  pure_quanta q_cap *
  page273_i50
#CELL
  pure_quanta q_cap *
  page273_i51
#CELL
  pure_quanta q_cap *
  page273_i52
#ISCELL
  standard offpage *
  page273_i53
#CELL
  pure_quanta q_cap *
  page273_i54
#ISCELL
  logical_power universal_gnd *
  page273_i55
#ISCELL
  logical_power vcc15 *
  page273_i56
#CELL
  pure_quanta q_cap *
  page273_i57
#ISCELL
  logical_power universal_gnd *
  page273_i58
#ISCELL
  logical_power vcc15 *
  page273_i59
#ISCELL
  logical_power universal_gnd *
  page273_i6
#ISCELL
  logical_power universal_gnd *
  page273_i60
#ISCELL
  logical_power universal_gnd *
  page273_i61
#ISCELL
  standard offpage *
  page273_i62
#ISCELL
  logical_power vcc15 *
  page273_i63
#CELL
  pure_quanta q_cap *
  page273_i64
#CELL
  pure_quanta q_cap *
  page273_i65
#ISCELL
  logical_power vcc15 *
  page273_i66
#CELL
  pure_quanta q_res *
  page273_i7
#ISCELL
  standard offpage *
  page273_i8
#ISCELL
  logical_power universal_gnd *
  page273_i9
